FILE_TYPE = CONNECTIVITY;
{Allegro Design Entry HDL 17.2-2016 S081 (4005846) 1/11/2022}
"PAGE_NUMBER" = 304;
0"NC";
1"P3V3_AUX\g";
2"P3V3_AUX\g";
3"P3V3_AUX\g";
4"P3V3_AUX\g";
5"P3V3_AUX\g";
6"P3V3_AUX\g";
7"P3V3_AUX\g";
8"P3V3_AUX\g";
9"GND\g";
10"GND\g";
11"GND\g";
12"GND\g";
13"GND\g";
14"GND\g";
15"GND\g";
16"GND\g";
17"LED_RST_PLD_CPU0_DRAM_GH_N";
18"RST_PLD_CPU0_DRAM_EF_N";
19"RST_PLD_CPU0_DRAM_GH_N";
20"LED_RST_PLD_CPU0_DRAM_EF_N_D";
21"RST_PLD_CPU1_DRAM_AB_N";
22"LED_RST_PLD_CPU1_DRAM_AB_N_D";
23"LED_RST_PLD_CPU1_DRAM_CD_N_D";
24"RST_PLD_CPU1_DRAM_CD_N";
25"LED_RST_PLD_CPU0_DRAM_CD_N";
26"LED_RST_PLD_CPU0_DRAM_CD_N_D";
27"RST_PLD_CPU0_DRAM_CD_N";
28"LED_RST_PLD_CPU1_DRAM_EF_N_D";
29"LED_RST_PLD_CPU1_DRAM_EF_N";
30"RST_PLD_CPU1_DRAM_EF_N";
31"LED_RST_PLD_CPU1_DRAM_GH_N_D";
32"RST_PLD_CPU1_DRAM_GH_N";
33"LED_RST_PLD_CPU1_DRAM_GH_N";
34"LED_RST_PLD_CPU0_DRAM_GH_N_D";
35"RST_PLD_CPU0_DRAM_AB_N";
36"LED_RST_PLD_CPU0_DRAM_AB_N_D";
37"LED_RST_PLD_CPU0_DRAM_EF_N";
38"LED_RST_PLD_CPU0_DRAM_AB_N";
39"LED_RST_PLD_CPU1_DRAM_CD_N";
40"LED_RST_PLD_CPU1_DRAM_AB_N";
%"UNIVERSAL_GND"
"1","(-2800,2225)","0","logical_power","I10";
;
CDS_LIB"logical_power"
HDL_POWER"GND";
"A"16;
%"Q_LED"
"1","(-1800,1175)","2","pure_quanta","I12";
;
PART_NUMBER"BEBL0172Z00"
COLOR"LED_BLUE"
MANUF_PN"LTST-C281TBKT-5A"
MATERIAL"IC"
PACK_TYPE"SMLF"
LOCATION"D67"
CDS_LIB"pure_quanta"
NEEDS_NO_SIZE"TRUE"
$SEC"1"
CDS_SEC"1";
"A"
$PN"A"37;
"C"
$PN"C"20;
%"UNIVERSAL_POWER"
"1","(275,0)","0","logical_power","I14";
;
HDL_POWER"P3V3_AUX"
CDS_LIB"logical_power";
"A"2;
%"UNIVERSAL_POWER"
"1","(150,1350)","0","logical_power","I16";
;
HDL_POWER"P3V3_AUX"
CDS_LIB"logical_power";
"A"3;
%"UNIVERSAL_GND"
"1","(-2800,3825)","0","logical_power","I19";
;
CDS_LIB"logical_power"
HDL_POWER"GND";
"A"15;
%"Q_LED"
"1","(-1775,2850)","2","pure_quanta","I20";
;
PART_NUMBER"BEBL0172Z00"
MATERIAL"IC"
PACK_TYPE"SMLF"
COLOR"LED_BLUE"
MANUF_PN"LTST-C281TBKT-5A"
LOCATION"D66"
NEEDS_NO_SIZE"TRUE"
CDS_LIB"pure_quanta"
$SEC"1"
CDS_SEC"1";
"A"
$PN"A"25;
"C"
$PN"C"26;
%"Q_LED"
"1","(-1775,4450)","2","pure_quanta","I21";
;
PART_NUMBER"BEBL0172Z00"
MATERIAL"IC"
PACK_TYPE"SMLF"
COLOR"LED_BLUE"
MANUF_PN"LTST-C281TBKT-5A"
LOCATION"D65"
NEEDS_NO_SIZE"TRUE"
CDS_LIB"pure_quanta"
$SEC"1"
CDS_SEC"1";
"A"
$PN"A"38;
"C"
$PN"C"36;
%"UNIVERSAL_POWER"
"1","(175,3025)","0","logical_power","I24";
;
HDL_POWER"P3V3_AUX"
CDS_LIB"logical_power";
"A"4;
%"UNIVERSAL_POWER"
"1","(175,4600)","0","logical_power","I26";
;
HDL_POWER"P3V3_AUX"
CDS_LIB"logical_power";
"A"1;
%"UNIVERSAL_GND"
"1","(1675,3800)","0","logical_power","I29";
;
CDS_LIB"logical_power"
HDL_POWER"GND";
"A"10;
%"Q_LED"
"1","(2700,3000)","2","pure_quanta","I31";
;
PART_NUMBER"BEBL0172Z00"
MATERIAL"IC"
COLOR"LED_BLUE"
MANUF_PN"LTST-C281TBKT-5A"
PACK_TYPE"SMLF"
LOCATION"D70"
CDS_LIB"pure_quanta"
NEEDS_NO_SIZE"TRUE"
$SEC"1"
CDS_SEC"1";
"A"
$PN"A"39;
"C"
$PN"C"23;
%"Q_LED"
"1","(2700,4425)","2","pure_quanta","I32";
;
PART_NUMBER"BEBL0172Z00"
PACK_TYPE"SMLF"
COLOR"LED_BLUE"
MATERIAL"IC"
MANUF_PN"LTST-C281TBKT-5A"
LOCATION"D69"
NEEDS_NO_SIZE"TRUE"
CDS_LIB"pure_quanta"
$SEC"1"
CDS_SEC"1";
"A"
$PN"A"40;
"C"
$PN"C"22;
%"UNIVERSAL_POWER"
"1","(4750,3175)","0","logical_power","I35";
;
HDL_POWER"P3V3_AUX"
CDS_LIB"logical_power";
"A"8;
%"UNIVERSAL_POWER"
"1","(4675,4600)","0","logical_power","I36";
;
HDL_POWER"P3V3_AUX"
CDS_LIB"logical_power";
"A"7;
%"Q_RES"
"1","(-400,4450)","0","pure_quanta","I49";
;
PART_NUMBER"CS11302FB03"
VALUE"130"
TOLERANCE"1%"
WATTAGE"1/16W"
PACK_TYPE"0402LF"
MATERIAL"CHIP"
LOCATION"R1371"
CDS_LIB"pure_quanta"
$SEC"1"
CDS_SEC"1";
"B"
$PN"2"1;
"A"
$PN"1"38;
%"Q_RES"
"1","(-475,2850)","0","pure_quanta","I50";
;
PART_NUMBER"CS11302FB03"
TOLERANCE"1%"
MATERIAL"CHIP"
WATTAGE"1/16W"
VALUE"130"
PACK_TYPE"0402LF"
$LOCATION"R3080"
CDS_LIB"pure_quanta"
CDS_LOCATION"R3080"
$SEC"1"
CDS_SEC"1";
"B"
$PN"2"4;
"A"
$PN"1"25;
%"Q_RES"
"1","(-500,1175)","0","pure_quanta","I51";
;
PART_NUMBER"CS11302FB03"
PACK_TYPE"0402LF"
MATERIAL"CHIP"
VALUE"130"
TOLERANCE"1%"
WATTAGE"1/16W"
$LOCATION"R3079"
CDS_LIB"pure_quanta"
CDS_LOCATION"R3079"
$SEC"1"
CDS_SEC"1";
"B"
$PN"2"3;
"A"
$PN"1"37;
%"Q_RES"
"1","(-350,-175)","0","pure_quanta","I52";
;
PART_NUMBER"CS11302FB03"
VALUE"130"
TOLERANCE"1%"
WATTAGE"1/16W"
PACK_TYPE"0402LF"
MATERIAL"CHIP"
$LOCATION"R3081"
CDS_LIB"pure_quanta"
CDS_LOCATION"R3081"
$SEC"1"
CDS_SEC"1";
"B"
$PN"2"2;
"A"
$PN"1"17;
%"Q_RES"
"1","(4100,3000)","0","pure_quanta","I53";
;
PART_NUMBER"CS11302FB03"
VALUE"130"
TOLERANCE"1%"
MATERIAL"CHIP"
WATTAGE"1/16W"
PACK_TYPE"0402LF"
$LOCATION"R3084"
CDS_LIB"pure_quanta"
CDS_LOCATION"R3084"
$SEC"1"
CDS_SEC"1";
"B"
$PN"2"8;
"A"
$PN"1"39;
%"Q_RES"
"1","(4000,4425)","0","pure_quanta","I54";
;
PART_NUMBER"CS11302FB03"
VALUE"130"
TOLERANCE"1%"
MATERIAL"CHIP"
WATTAGE"1/16W"
PACK_TYPE"0402LF"
$LOCATION"R3082"
CDS_LIB"pure_quanta"
CDS_LOCATION"R3082"
$SEC"1"
CDS_SEC"1";
"B"
$PN"2"7;
"A"
$PN"1"40;
%"UNIVERSAL_POWER"
"1","(4675,1425)","0","logical_power","I55";
;
HDL_POWER"P3V3_AUX"
CDS_LIB"logical_power";
"A"5;
%"UNIVERSAL_POWER"
"1","(4800,75)","0","logical_power","I56";
;
HDL_POWER"P3V3_AUX"
CDS_LIB"logical_power";
"A"6;
%"Q_RES"
"1","(4025,1250)","0","pure_quanta","I57";
;
PART_NUMBER"CS11302FB03"
VALUE"130"
TOLERANCE"1%"
MATERIAL"CHIP"
WATTAGE"1/16W"
PACK_TYPE"0402LF"
$LOCATION"R3083"
CDS_LIB"pure_quanta"
CDS_LOCATION"R3083"
$SEC"1"
CDS_SEC"1";
"B"
$PN"2"5;
"A"
$PN"1"29;
%"Q_LED"
"1","(2725,1250)","2","pure_quanta","I58";
;
PART_NUMBER"BEBL0172Z00"
MATERIAL"IC"
MANUF_PN"LTST-C281TBKT-5A"
COLOR"LED_BLUE"
PACK_TYPE"SMLF"
LOCATION"D71"
NEEDS_NO_SIZE"TRUE"
CDS_LIB"pure_quanta"
$SEC"1"
CDS_SEC"1";
"A"
$PN"A"29;
"C"
$PN"C"28;
%"UNIVERSAL_GND"
"1","(1700,625)","0","logical_power","I59";
;
CDS_LIB"logical_power"
HDL_POWER"GND";
"A"11;
%"UNIVERSAL_GND"
"1","(-2625,-875)","0","logical_power","I6";
;
HDL_POWER"GND"
CDS_LIB"logical_power";
"A"13;
%"Q_RES"
"1","(4175,-100)","0","pure_quanta","I62";
;
PART_NUMBER"CS11302FB03"
MATERIAL"CHIP"
PACK_TYPE"0402LF"
WATTAGE"1/16W"
TOLERANCE"1%"
VALUE"130"
$LOCATION"R3085"
CDS_LIB"pure_quanta"
CDS_LOCATION"R3085"
$SEC"1"
CDS_SEC"1";
"B"
$PN"2"6;
"A"
$PN"1"33;
%"Q_LED"
"1","(2875,-100)","2","pure_quanta","I63";
;
PART_NUMBER"BEBL0172Z00"
MATERIAL"IC"
COLOR"LED_BLUE"
PACK_TYPE"SMLF"
MANUF_PN"LTST-C281TBKT-5A"
LOCATION"D72"
NEEDS_NO_SIZE"TRUE"
CDS_LIB"pure_quanta"
$SEC"1"
CDS_SEC"1";
"A"
$PN"A"33;
"C"
$PN"C"31;
%"UNIVERSAL_GND"
"1","(1900,-800)","0","logical_power","I64";
;
CDS_LIB"logical_power"
HDL_POWER"GND";
"A"12;
%"UNIVERSAL_GND"
"1","(1675,2400)","0","logical_power","I67";
;
HDL_POWER"GND"
CDS_LIB"logical_power";
"A"9;
%"MOSFET_NCH_DUAL"
"1","(-2850,4175)","0","pure_quanta","I68";
;
PART_NUMBER"BAM60080000"
PART_TYPE"SMLF"
MATERIAL"IC"
VALUE"NX6008NBKS"
$LOCATION"Q98"
CDS_LIB"pure_quanta"
CDS_LMAN_SYM_OUTLINE"-150,150,150,-150"
NEEDS_NO_SIZE"TRUE"
CDS_LOCATION"Q98"
$SEC"1"
CDS_SEC"1";
"D1"
$PN"6"36;
"G1"
$PN"2"35;
"S1"
$PN"1"15;
%"MOSFET_NCH_DUAL"
"2","(-2850,2575)","0","pure_quanta","I69";
;
PART_NUMBER"BAM60080000"
MATERIAL"IC"
PART_TYPE"SMLF"
VALUE"NX6008NBKS"
$LOCATION"Q98"
CDS_LIB"pure_quanta"
CDS_LMAN_SYM_OUTLINE"-150,150,150,-150"
NEEDS_NO_SIZE"TRUE"
CDS_LOCATION"Q98"
$SEC"2"
CDS_SEC"2";
"S2"
$PN"4"16;
"G2"
$PN"5"27;
"D2"
$PN"3"26;
%"MOSFET_NCH_DUAL"
"2","(-2675,-450)","0","pure_quanta","I70";
;
PART_NUMBER"BAM60080000"
MATERIAL"IC"
VALUE"NX6008NBKS"
PART_TYPE"SMLF"
$LOCATION"Q97"
CDS_LIB"pure_quanta"
CDS_LMAN_SYM_OUTLINE"-150,150,150,-150"
NEEDS_NO_SIZE"TRUE"
CDS_LOCATION"Q97"
$SEC"2"
CDS_SEC"2";
"S2"
$PN"4"13;
"G2"
$PN"5"19;
"D2"
$PN"3"34;
%"MOSFET_NCH_DUAL"
"1","(-2875,900)","0","pure_quanta","I71";
;
PART_NUMBER"BAM60080000"
PART_TYPE"SMLF"
VALUE"NX6008NBKS"
MATERIAL"IC"
$LOCATION"Q97"
NEEDS_NO_SIZE"TRUE"
CDS_LMAN_SYM_OUTLINE"-150,150,150,-150"
CDS_LIB"pure_quanta"
CDS_LOCATION"Q97"
$SEC"1"
CDS_SEC"1";
"D1"
$PN"6"20;
"G1"
$PN"2"18;
"S1"
$PN"1"14;
%"MOSFET_NCH_DUAL"
"1","(1625,2725)","0","pure_quanta","I72";
;
PART_NUMBER"BAM60080000"
PART_TYPE"SMLF"
MATERIAL"IC"
VALUE"NX6008NBKS"
$LOCATION"Q99"
CDS_LIB"pure_quanta"
CDS_LMAN_SYM_OUTLINE"-150,150,150,-150"
NEEDS_NO_SIZE"TRUE"
CDS_LOCATION"Q99"
$SEC"1"
CDS_SEC"1";
"D1"
$PN"6"23;
"G1"
$PN"2"24;
"S1"
$PN"1"9;
%"MOSFET_NCH_DUAL"
"1","(1650,975)","0","pure_quanta","I74";
;
PART_NUMBER"BAM60080000"
PART_TYPE"SMLF"
VALUE"NX6008NBKS"
MATERIAL"IC"
$LOCATION"Q100"
NEEDS_NO_SIZE"TRUE"
CDS_LMAN_SYM_OUTLINE"-150,150,150,-150"
CDS_LIB"pure_quanta"
CDS_LOCATION"Q100"
$SEC"1"
CDS_SEC"1";
"D1"
$PN"6"28;
"G1"
$PN"2"30;
"S1"
$PN"1"11;
%"MOSFET_NCH_DUAL"
"2","(1850,-375)","0","pure_quanta","I75";
;
PART_NUMBER"BAM60080000"
PART_TYPE"SMLF"
MATERIAL"IC"
VALUE"NX6008NBKS"
$LOCATION"Q100"
CDS_LIB"pure_quanta"
CDS_LMAN_SYM_OUTLINE"-150,150,150,-150"
NEEDS_NO_SIZE"TRUE"
CDS_LOCATION"Q100"
$SEC"2"
CDS_SEC"2";
"S2"
$PN"4"12;
"G2"
$PN"5"32;
"D2"
$PN"3"31;
%"MOSFET_NCH_DUAL"
"1","(1625,4150)","0","pure_quanta","I76";
;
PART_NUMBER"BAM60080000"
PART_TYPE"SMLF"
MATERIAL"IC"
VALUE"NX6008NBKS"
$LOCATION"Q105"
NEEDS_NO_SIZE"TRUE"
CDS_LMAN_SYM_OUTLINE"-150,150,150,-150"
CDS_LIB"pure_quanta"
CDS_LOCATION"Q105"
$SEC"1"
CDS_SEC"1";
"D1"
$PN"6"22;
"G1"
$PN"2"21;
"S1"
$PN"1"10;
%"UNIVERSAL_GND"
"1","(-2825,550)","0","logical_power","I8";
;
HDL_POWER"GND"
CDS_LIB"logical_power";
"A"14;
%"Q_LED"
"1","(-1650,-175)","2","pure_quanta","I9";
;
PART_NUMBER"BEBL0172Z00"
PACK_TYPE"SMLF"
MATERIAL"IC"
COLOR"LED_BLUE"
MANUF_PN"LTST-C281TBKT-5A"
LOCATION"D68"
CDS_LIB"pure_quanta"
NEEDS_NO_SIZE"TRUE"
$SEC"1"
CDS_SEC"1";
"A"
$PN"A"17;
"C"
$PN"C"34;
END.
